# S9S_MB_2U (Grand Teton) — schematic netlist excerpt (pin names and nets, part order shuffled) for the footprints in the layout excerpt that follows; sources: Cadence DE-HDL packaged netlist, KiCad conversion of 03242023_DA0F0TMBIJ0_F0T_Motherboard_J_brd_V01_OCP.brd

PC1845  Q_CAPP  220UF 6.3V 20% ALUM  pkg SMLF  page 258 : A = P5V_AUX ; B = GND
R4681  Q_RES  100K 1% CHIP  pkg 0402LF  page 260 : A = PWRGD_P3V3_R1 ; B = GND
C1544  Q_CAP_DIFFBUS  DIFF BUS_0.22UF 6.3V 20% X6S  pkg C0201  page 177 : \1\ = P5E_CPU1_PE3_TX_C_DN<1> ; \2\ = P5E_CPU1_PE3_TX_DN<1>

(kicad_pcb
	(version 20260206)
	(generator "pcbnew")
	(generator_version "10.0")
	(general
		(thickness 1.6)
		(legacy_teardrops no)
	)
	(paper "A4")
	(title_block
		(title "03242023_DA0F0TMBIJ0_F0T_Motherboard_J_brd_V01_OCP.brd")
		(comment 1 "Grand Teton / footprints 856-858 of 6105")
	)
	(layers
		(0 "F.Cu" signal "TOP")
		(4 "In1.Cu" signal "GND")
		(6 "In2.Cu" signal "IN1")
		(8 "In3.Cu" signal "GND1")
		(10 "In4.Cu" signal "IN2")
		(12 "In5.Cu" signal "GND2")
		(14 "In6.Cu" signal "IN3")
		(16 "In7.Cu" signal "GND3")
		(18 "In8.Cu" signal "VCC")
		(20 "In9.Cu" signal "VCC1")
		(22 "In10.Cu" signal "GND4")
		(24 "In11.Cu" signal "IN4")
		(26 "In12.Cu" signal "GND5")
		(28 "In13.Cu" signal "IN5")
		(30 "In14.Cu" signal "GND6")
		(32 "In15.Cu" signal "IN6")
		(34 "In16.Cu" signal "GND7")
		(2 "B.Cu" signal "BOTTOM")
		(9 "F.Adhes" user "F.Adhesive")
		(11 "B.Adhes" user "B.Adhesive")
		(13 "F.Paste" user "Package Geometry/Pastemask Top")
		(15 "B.Paste" user "Package Geometry/Pastemask Bottom")
		(5 "F.SilkS" user "Ref Des/Silkscreen Top")
		(7 "B.SilkS" user "Ref Des/Silkscreen Bottom")
		(1 "F.Mask" user "Board Geometry/Soldermask Top")
		(3 "B.Mask" user "Board Geometry/Soldermask Bottom")
		(17 "Dwgs.User" user "User.Drawings")
		(19 "Cmts.User" user "User.Comments")
		(21 "Eco1.User" user "User.Eco1")
		(23 "Eco2.User" user "User.Eco2")
		(25 "Edge.Cuts" user "Board Geometry/Outline")
		(27 "Margin" user)
		(31 "F.CrtYd" user "Package Geometry/Place Bound Top")
		(29 "B.CrtYd" user "Package Geometry/Place Bound Bottom")
		(35 "F.Fab" user "Ref Des/Assembly Top")
		(33 "B.Fab" user "Ref Des/Assembly Bottom")
	)
	(footprint ""
		(layer "F.Cu")
		(at 437.425846 -387.527292 180)
		(property "Reference" "PC1845"
			(at 0 0 180)
			(layer "F.SilkS")
			(hide yes)
			(effects
				(font
					(size 1.27 1.27)
				)
			)
		)
		(property "Value" ""
			(at 0 0 180)
			(layer "F.Fab")
			(effects
				(font
					(size 1.27 1.27)
				)
			)
		)
		(duplicate_pad_numbers_are_jumpers no)
		(fp_line
			(start 2.750058 2.750058)
			(end 2.750058 0.9398)
			(stroke
				(width 0.1524)
				(type default)
			)
			(layer "F.SilkS")
		)
		(fp_line
			(start 2.750058 -0.9398)
			(end 2.750058 -2.750058)
			(stroke
				(width 0.1524)
				(type default)
			)
			(layer "F.SilkS")
		)
		(fp_line
			(start 2.750058 -2.750058)
			(end -1.988058 -2.750058)
			(stroke
				(width 0.1524)
				(type default)
			)
			(layer "F.SilkS")
		)
		(fp_line
			(start -1.988058 2.750058)
			(end 2.750058 2.750058)
			(stroke
				(width 0.1524)
				(type default)
			)
			(layer "F.SilkS")
		)
		(fp_line
			(start -1.988058 -2.750058)
			(end -2.750058 -1.988058)
			(stroke
				(width 0.1524)
				(type default)
			)
			(layer "F.SilkS")
		)
		(fp_line
			(start -2.750058 1.988058)
			(end -1.988058 2.750058)
			(stroke
				(width 0.1524)
				(type default)
			)
			(layer "F.SilkS")
		)
		(fp_line
			(start -2.750058 0.9398)
			(end -2.750058 1.988058)
			(stroke
				(width 0.1524)
				(type default)
			)
			(layer "F.SilkS")
		)
		(fp_line
			(start -2.750058 -1.988058)
			(end -2.750058 -0.9398)
			(stroke
				(width 0.1524)
				(type default)
			)
			(layer "F.SilkS")
		)
		(fp_line
			(start 2.750058 2.750058)
			(end 2.750058 -2.750058)
			(stroke
				(width 0.1)
				(type default)
			)
			(layer "F.Fab")
		)
		(fp_line
			(start 2.750058 -2.750058)
			(end -2.750058 -2.750058)
			(stroke
				(width 0.1)
				(type default)
			)
			(layer "F.Fab")
		)
		(fp_line
			(start -2.750058 2.750058)
			(end 2.750058 2.750058)
			(stroke
				(width 0.1)
				(type default)
			)
			(layer "F.Fab")
		)
		(fp_line
			(start -2.750058 -2.750058)
			(end -2.750058 2.750058)
			(stroke
				(width 0.1)
				(type default)
			)
			(layer "F.Fab")
		)
		(pad "1" smd rect
			(at -2.199894 0 270)
			(size 1.6002 3.0226)
			(layers "F.Cu" "F.Mask" "F.Paste")
			(net "P5V_AUX")
		)
		(pad "2" smd rect
			(at 2.199894 0 270)
			(size 1.6002 3.0226)
			(layers "F.Cu" "F.Mask" "F.Paste")
			(net "GND")
		)
	)
	(footprint ""
		(layer "F.Cu")
		(at 164.361114 -408.517344 -90)
		(property "Reference" "C1544"
			(at 0 0 270)
			(layer "F.SilkS")
			(hide yes)
			(effects
				(font
					(size 1.27 1.27)
				)
			)
		)
		(property "Value" ""
			(at 0 0 270)
			(layer "F.Fab")
			(effects
				(font
					(size 1.27 1.27)
				)
			)
		)
		(duplicate_pad_numbers_are_jumpers no)
		(fp_line
			(start -0.299974 0.150114)
			(end -0.299974 -0.150114)
			(stroke
				(width 0.1)
				(type default)
			)
			(layer "F.Fab")
		)
		(fp_line
			(start 0.299974 0.150114)
			(end -0.299974 0.150114)
			(stroke
				(width 0.1)
				(type default)
			)
			(layer "F.Fab")
		)
		(fp_line
			(start -0.299974 -0.150114)
			(end 0.299974 -0.150114)
			(stroke
				(width 0.1)
				(type default)
			)
			(layer "F.Fab")
		)
		(fp_line
			(start 0.299974 -0.150114)
			(end 0.299974 0.150114)
			(stroke
				(width 0.1)
				(type default)
			)
			(layer "F.Fab")
		)
		(pad "1" smd rect
			(at -0.2667 0 270)
			(size 0.3048 0.381)
			(layers "F.Cu" "F.Mask" "F.Paste")
			(net "P5E_CPU1_PE3_TX_C_DN<1>")
		)
		(pad "2" smd rect
			(at 0.2667 0 270)
			(size 0.3048 0.381)
			(layers "F.Cu" "F.Mask" "F.Paste")
			(net "P5E_CPU1_PE3_TX_DN<1>")
		)
	)
	(footprint ""
		(layer "F.Cu")
		(at 417.66744 -51.87696 90)
		(property "Reference" "R4681"
			(at 0 0 90)
			(layer "F.SilkS")
			(hide yes)
			(effects
				(font
					(size 1.27 1.27)
				)
			)
		)
		(property "Value" ""
			(at 0 0 90)
			(layer "F.Fab")
			(effects
				(font
					(size 1.27 1.27)
				)
			)
		)
		(duplicate_pad_numbers_are_jumpers no)
		(fp_line
			(start 0.7874 -0.4064)
			(end 0.7874 0.4064)
			(stroke
				(width 0.1524)
				(type default)
			)
			(layer "F.SilkS")
		)
		(fp_line
			(start -0.7874 -0.4064)
			(end 0.7874 -0.4064)
			(stroke
				(width 0.1524)
				(type default)
			)
			(layer "F.SilkS")
		)
		(fp_line
			(start 0.7874 0.4064)
			(end -0.7874 0.4064)
			(stroke
				(width 0.1524)
				(type default)
			)
			(layer "F.SilkS")
		)
		(fp_line
			(start -0.7874 0.4064)
			(end -0.7874 -0.4064)
			(stroke
				(width 0.1524)
				(type default)
			)
			(layer "F.SilkS")
		)
		(fp_line
			(start -0.12065 -0.305054)
			(end -0.12065 -0.2794)
			(stroke
				(width 0.1)
				(type default)
			)
			(layer "F.Fab")
		)
		(fp_line
			(start -0.67945 -0.305054)
			(end -0.12065 -0.305054)
			(stroke
				(width 0.1)
				(type default)
			)
			(layer "F.Fab")
		)
		(fp_line
			(start 0.67945 -0.3048)
			(end 0.67945 0.3048)
			(stroke
				(width 0.1)
				(type default)
			)
			(layer "F.Fab")
		)
		(fp_line
			(start 0.12065 -0.3048)
			(end 0.67945 -0.3048)
			(stroke
				(width 0.1)
				(type default)
			)
			(layer "F.Fab")
		)
		(fp_line
			(start 0.12065 -0.2794)
			(end 0.12065 -0.3048)
			(stroke
				(width 0.1)
				(type default)
			)
			(layer "F.Fab")
		)
		(fp_line
			(start -0.12065 -0.2794)
			(end 0.12065 -0.2794)
			(stroke
				(width 0.1)
				(type default)
			)
			(layer "F.Fab")
		)
		(fp_line
			(start 0.120396 0.2794)
			(end -0.12065 0.2794)
			(stroke
				(width 0.1)
				(type default)
			)
			(layer "F.Fab")
		)
		(fp_line
			(start -0.12065 0.2794)
			(end -0.12065 0.3048)
			(stroke
				(width 0.1)
				(type default)
			)
			(layer "F.Fab")
		)
		(fp_line
			(start 0.67945 0.3048)
			(end 0.120396 0.3048)
			(stroke
				(width 0.1)
				(type default)
			)
			(layer "F.Fab")
		)
		(fp_line
			(start 0.120396 0.3048)
			(end 0.120396 0.2794)
			(stroke
				(width 0.1)
				(type default)
			)
			(layer "F.Fab")
		)
		(fp_line
			(start -0.12065 0.3048)
			(end -0.67945 0.3048)
			(stroke
				(width 0.1)
				(type default)
			)
			(layer "F.Fab")
		)
		(fp_line
			(start -0.67945 0.3048)
			(end -0.67945 -0.305054)
			(stroke
				(width 0.1)
				(type default)
			)
			(layer "F.Fab")
		)
		(pad "1" smd circle
			(at -0.40005 0 90)
			(size 0 0)
			(layers "F.Cu" "F.Mask" "F.Paste")
			(net "PWRGD_P3V3_R1")
		)
		(pad "2" smd circle
			(at 0.40005 0 90)
			(size 0 0)
			(layers "F.Cu" "F.Mask" "F.Paste")
			(net "GND")
		)
	)
)
